# T6G (Grand Teton) — schematic netlist excerpt (pin names and nets, part order shuffled) for the footprints in the layout excerpt that follows; sources: Cadence DE-HDL packaged netlist, KiCad conversion of 04192023_DAF0TMB3IC0_F0TG_MB_C_brd_V02_OCP.brd

R1243  Q_RES  0 5% CHIP  pkg 0402LF  page 258 : A = SMB_ADC_SDA_R ; B = SMB_SEN_TIC_2_3V3AUX_SDA
C7018  Q_CAPP  470UF 2.5V 20% SPCAP  pkg SMLF  page 312 : A = P0V9_CPU0_RT3_2A ; B = GND

(kicad_pcb
	(version 20260206)
	(generator "pcbnew")
	(generator_version "10.0")
	(general
		(thickness 1.6)
		(legacy_teardrops no)
	)
	(paper "A4")
	(title_block
		(title "04192023_DAF0TMB3IC0_F0TG_MB_C_brd_V02_OCP.brd")
		(comment 1 "Grand Teton / footprints 5014-5015 of 8354")
	)
	(layers
		(0 "F.Cu" signal "TOP")
		(4 "In1.Cu" signal "GND")
		(6 "In2.Cu" signal "IN1")
		(8 "In3.Cu" signal "GND1")
		(10 "In4.Cu" signal "IN2")
		(12 "In5.Cu" signal "GND2")
		(14 "In6.Cu" signal "IN3")
		(16 "In7.Cu" signal "GND3")
		(18 "In8.Cu" signal "VCC")
		(20 "In9.Cu" signal "VCC1")
		(22 "In10.Cu" signal "GND4")
		(24 "In11.Cu" signal "IN4")
		(26 "In12.Cu" signal "GND5")
		(28 "In13.Cu" signal "IN5")
		(30 "In14.Cu" signal "GND6")
		(32 "In15.Cu" signal "IN6")
		(34 "In16.Cu" signal "GND7")
		(2 "B.Cu" signal "BOTTOM")
		(9 "F.Adhes" user "F.Adhesive")
		(11 "B.Adhes" user "B.Adhesive")
		(13 "F.Paste" user "Package Geometry/Pastemask Top")
		(15 "B.Paste" user "Package Geometry/Pastemask Bottom")
		(5 "F.SilkS" user "Ref Des/Silkscreen Top")
		(7 "B.SilkS" user "Ref Des/Silkscreen Bottom")
		(1 "F.Mask" user "Board Geometry/Soldermask Top")
		(3 "B.Mask" user "Board Geometry/Soldermask Bottom")
		(17 "Dwgs.User" user "User.Drawings")
		(19 "Cmts.User" user "User.Comments")
		(21 "Eco1.User" user "User.Eco1")
		(23 "Eco2.User" user "User.Eco2")
		(25 "Edge.Cuts" user "Board Geometry/Outline")
		(27 "Margin" user)
		(31 "F.CrtYd" user "Package Geometry/Place Bound Top")
		(29 "B.CrtYd" user "Package Geometry/Place Bound Bottom")
		(35 "F.Fab" user "Ref Des/Assembly Top")
		(33 "B.Fab" user "Ref Des/Assembly Bottom")
	)
	(footprint ""
		(layer "B.Cu")
		(at 216.123774 -323.588634 180)
		(property "Reference" "R1243"
			(at 0 0 0)
			(layer "B.SilkS")
			(hide yes)
			(effects
				(font
					(size 1.27 1.27)
				)
				(justify mirror)
			)
		)
		(property "Value" ""
			(at 0 0 0)
			(layer "B.Fab")
			(effects
				(font
					(size 1.27 1.27)
				)
				(justify mirror)
			)
		)
		(duplicate_pad_numbers_are_jumpers no)
		(fp_line
			(start 0.7874 0.4064)
			(end 0.7874 -0.4064)
			(stroke
				(width 0.1524)
				(type default)
			)
			(layer "B.SilkS")
		)
		(fp_line
			(start 0.7874 -0.4064)
			(end -0.7874 -0.4064)
			(stroke
				(width 0.1524)
				(type default)
			)
			(layer "B.SilkS")
		)
		(fp_line
			(start -0.7874 0.4064)
			(end 0.7874 0.4064)
			(stroke
				(width 0.1524)
				(type default)
			)
			(layer "B.SilkS")
		)
		(fp_line
			(start -0.7874 -0.4064)
			(end -0.7874 0.4064)
			(stroke
				(width 0.1524)
				(type default)
			)
			(layer "B.SilkS")
		)
		(fp_line
			(start 0.67945 0.3048)
			(end 0.67945 -0.305054)
			(stroke
				(width 0.1)
				(type default)
			)
			(layer "B.Fab")
		)
		(fp_line
			(start 0.67945 -0.305054)
			(end 0.12065 -0.305054)
			(stroke
				(width 0.1)
				(type default)
			)
			(layer "B.Fab")
		)
		(fp_line
			(start 0.12065 0.3048)
			(end 0.67945 0.3048)
			(stroke
				(width 0.1)
				(type default)
			)
			(layer "B.Fab")
		)
		(fp_line
			(start 0.12065 0.2794)
			(end 0.12065 0.3048)
			(stroke
				(width 0.1)
				(type default)
			)
			(layer "B.Fab")
		)
		(fp_line
			(start 0.12065 -0.2794)
			(end -0.12065 -0.2794)
			(stroke
				(width 0.1)
				(type default)
			)
			(layer "B.Fab")
		)
		(fp_line
			(start 0.12065 -0.305054)
			(end 0.12065 -0.2794)
			(stroke
				(width 0.1)
				(type default)
			)
			(layer "B.Fab")
		)
		(fp_line
			(start -0.120396 0.3048)
			(end -0.120396 0.2794)
			(stroke
				(width 0.1)
				(type default)
			)
			(layer "B.Fab")
		)
		(fp_line
			(start -0.120396 0.2794)
			(end 0.12065 0.2794)
			(stroke
				(width 0.1)
				(type default)
			)
			(layer "B.Fab")
		)
		(fp_line
			(start -0.12065 -0.2794)
			(end -0.12065 -0.3048)
			(stroke
				(width 0.1)
				(type default)
			)
			(layer "B.Fab")
		)
		(fp_line
			(start -0.12065 -0.3048)
			(end -0.67945 -0.3048)
			(stroke
				(width 0.1)
				(type default)
			)
			(layer "B.Fab")
		)
		(fp_line
			(start -0.67945 0.3048)
			(end -0.120396 0.3048)
			(stroke
				(width 0.1)
				(type default)
			)
			(layer "B.Fab")
		)
		(fp_line
			(start -0.67945 -0.3048)
			(end -0.67945 0.3048)
			(stroke
				(width 0.1)
				(type default)
			)
			(layer "B.Fab")
		)
		(pad "1" smd circle
			(at 0.40005 0)
			(size 0 0)
			(layers "B.Cu" "B.Mask" "B.Paste")
			(net "SMB_ADC_SDA_R")
		)
		(pad "2" smd circle
			(at -0.40005 0)
			(size 0 0)
			(layers "B.Cu" "B.Mask" "B.Paste")
			(net "SMB_SEN_TIC_2_3V3AUX_SDA")
		)
	)
	(footprint ""
		(layer "B.Cu")
		(at 385.06781 -389.49503)
		(property "Reference" "C7018"
			(at 2.82956 3.177032 0)
			(unlocked yes)
			(layer "B.SilkS")
			(effects
				(font
					(size 0.7874 0.5842)
					(thickness 0.1524)
				)
				(justify left mirror)
			)
		)
		(property "Value" ""
			(at 0 0 0)
			(layer "B.Fab")
			(effects
				(font
					(size 1.27 1.27)
				)
				(justify mirror)
			)
		)
		(duplicate_pad_numbers_are_jumpers no)
		(fp_line
			(start -4.53898 -2.15011)
			(end -4.53898 2.15011)
			(stroke
				(width 0.1524)
				(type default)
			)
			(layer "B.SilkS")
		)
		(fp_line
			(start -4.53898 2.15011)
			(end 4.53898 2.15011)
			(stroke
				(width 0.1524)
				(type default)
			)
			(layer "B.SilkS")
		)
		(fp_line
			(start 4.53898 -2.150618)
			(end 4.539742 2.152142)
			(stroke
				(width 0.1524)
				(type default)
			)
			(layer "B.SilkS")
		)
		(fp_line
			(start 4.53898 -2.15011)
			(end -4.53898 -2.15011)
			(stroke
				(width 0.1524)
				(type default)
			)
			(layer "B.SilkS")
		)
		(fp_line
			(start 4.53898 2.15011)
			(end 4.53898 -2.15011)
			(stroke
				(width 0.1524)
				(type default)
			)
			(layer "B.SilkS")
		)
		(fp_line
			(start 4.69138 -2.150618)
			(end 4.692396 2.161032)
			(stroke
				(width 0.1524)
				(type default)
			)
			(layer "B.SilkS")
		)
		(fp_line
			(start 4.83108 2.150364)
			(end 4.447794 2.149348)
			(stroke
				(width 0.1524)
				(type default)
			)
			(layer "B.SilkS")
		)
		(fp_line
			(start 4.84378 -2.150618)
			(end 4.53898 -2.150618)
			(stroke
				(width 0.1524)
				(type default)
			)
			(layer "B.SilkS")
		)
		(fp_line
			(start 4.84378 -2.150618)
			(end 4.842256 2.163064)
			(stroke
				(width 0.1524)
				(type default)
			)
			(layer "B.SilkS")
		)
		(fp_line
			(start -3.64998 -2.15011)
			(end -3.64998 2.15011)
			(stroke
				(width 0.1)
				(type default)
			)
			(layer "B.Fab")
		)
		(fp_line
			(start -3.64998 2.15011)
			(end 3.64998 2.15011)
			(stroke
				(width 0.1)
				(type default)
			)
			(layer "B.Fab")
		)
		(fp_line
			(start 3.64998 -2.15011)
			(end -3.64998 -2.15011)
			(stroke
				(width 0.1)
				(type default)
			)
			(layer "B.Fab")
		)
		(fp_line
			(start 3.64998 2.15011)
			(end 3.64998 -2.15011)
			(stroke
				(width 0.1)
				(type default)
			)
			(layer "B.Fab")
		)
		(fp_text user "-"
			(at -3.017774 2.359152 0)
			(unlocked yes)
			(layer "B.SilkS")
			(effects
				(font
					(size 1.905 1.4224)
					(thickness 0.1524)
				)
				(justify left mirror)
			)
		)
		(fp_text user "+"
			(at 6.214872 -0.337058 0)
			(unlocked yes)
			(layer "B.SilkS")
			(effects
				(font
					(size 1.905 1.4224)
					(thickness 0.1524)
				)
				(justify left mirror)
			)
		)
		(fp_text user "-"
			(at -4.313174 -0.094488 0)
			(unlocked yes)
			(layer "B.Fab")
			(effects
				(font
					(size 1.905 1.4224)
					(thickness 0.1524)
				)
				(justify left mirror)
			)
		)
		(fp_text user "+"
			(at 6.214872 -0.337058 0)
			(unlocked yes)
			(layer "B.Fab")
			(effects
				(font
					(size 1.905 1.4224)
					(thickness 0.1524)
				)
				(justify left mirror)
			)
		)
		(pad "1" smd rect
			(at 3.199892 0 180)
			(size 2.413 2.8194)
			(layers "B.Cu" "B.Mask" "B.Paste")
			(net "P0V9_CPU0_RT3_2A")
		)
		(pad "2" smd rect
			(at -3.199892 0 180)
			(size 2.413 2.8194)
			(layers "B.Cu" "B.Mask" "B.Paste")
			(net "GND")
		)
	)
)
